# S9S_MB_2U (Grand Teton) — schematic netlist excerpt (pin names and nets, part order shuffled) for the footprints in the layout excerpt that follows; sources: Cadence DE-HDL packaged netlist, KiCad conversion of 03242023_DA0F0TMBIJ0_F0T_Motherboard_J_brd_V01_OCP.brd

R2923  Q_RES  4.7K 5% EMPTY  pkg 0402LF  page 227 : A = P3V3_AUX ; B = PU_U181_INT
PC1850  Q_CAP  22UF 16V 20% X6S  pkg C0805  page 258 : A = SW_P5V_AUX_FLT ; B = GND
R4394  Q_RES  33.2 1% CHIP  pkg 0402LF  page 225 : A = H_CPU_ERR2_LVC2_R_N ; B = H_CPU_ERR2_PCH_R_N

(kicad_pcb
	(version 20260206)
	(generator "pcbnew")
	(generator_version "10.0")
	(general
		(thickness 1.6)
		(legacy_teardrops no)
	)
	(paper "A4")
	(title_block
		(title "03242023_DA0F0TMBIJ0_F0T_Motherboard_J_brd_V01_OCP.brd")
		(comment 1 "Grand Teton / footprints 2699-2701 of 6105")
	)
	(layers
		(0 "F.Cu" signal "TOP")
		(4 "In1.Cu" signal "GND")
		(6 "In2.Cu" signal "IN1")
		(8 "In3.Cu" signal "GND1")
		(10 "In4.Cu" signal "IN2")
		(12 "In5.Cu" signal "GND2")
		(14 "In6.Cu" signal "IN3")
		(16 "In7.Cu" signal "GND3")
		(18 "In8.Cu" signal "VCC")
		(20 "In9.Cu" signal "VCC1")
		(22 "In10.Cu" signal "GND4")
		(24 "In11.Cu" signal "IN4")
		(26 "In12.Cu" signal "GND5")
		(28 "In13.Cu" signal "IN5")
		(30 "In14.Cu" signal "GND6")
		(32 "In15.Cu" signal "IN6")
		(34 "In16.Cu" signal "GND7")
		(2 "B.Cu" signal "BOTTOM")
		(9 "F.Adhes" user "F.Adhesive")
		(11 "B.Adhes" user "B.Adhesive")
		(13 "F.Paste" user "Package Geometry/Pastemask Top")
		(15 "B.Paste" user "Package Geometry/Pastemask Bottom")
		(5 "F.SilkS" user "Ref Des/Silkscreen Top")
		(7 "B.SilkS" user "Ref Des/Silkscreen Bottom")
		(1 "F.Mask" user "Board Geometry/Soldermask Top")
		(3 "B.Mask" user "Board Geometry/Soldermask Bottom")
		(17 "Dwgs.User" user "User.Drawings")
		(19 "Cmts.User" user "User.Comments")
		(21 "Eco1.User" user "User.Eco1")
		(23 "Eco2.User" user "User.Eco2")
		(25 "Edge.Cuts" user "Board Geometry/Outline")
		(27 "Margin" user)
		(31 "F.CrtYd" user "Package Geometry/Place Bound Top")
		(29 "B.CrtYd" user "Package Geometry/Place Bound Bottom")
		(35 "F.Fab" user "Ref Des/Assembly Top")
		(33 "B.Fab" user "Ref Des/Assembly Bottom")
	)
	(footprint ""
		(layer "F.Cu")
		(at 146.959828 -92.622878 -90)
		(property "Reference" "R4394"
			(at 0 0 270)
			(layer "F.SilkS")
			(hide yes)
			(effects
				(font
					(size 1.27 1.27)
				)
			)
		)
		(property "Value" ""
			(at 0 0 270)
			(layer "F.Fab")
			(effects
				(font
					(size 1.27 1.27)
				)
			)
		)
		(duplicate_pad_numbers_are_jumpers no)
		(fp_line
			(start -0.7874 0.4064)
			(end -0.7874 -0.4064)
			(stroke
				(width 0.1524)
				(type default)
			)
			(layer "F.SilkS")
		)
		(fp_line
			(start 0.7874 0.4064)
			(end -0.7874 0.4064)
			(stroke
				(width 0.1524)
				(type default)
			)
			(layer "F.SilkS")
		)
		(fp_line
			(start -0.7874 -0.4064)
			(end 0.7874 -0.4064)
			(stroke
				(width 0.1524)
				(type default)
			)
			(layer "F.SilkS")
		)
		(fp_line
			(start 0.7874 -0.4064)
			(end 0.7874 0.4064)
			(stroke
				(width 0.1524)
				(type default)
			)
			(layer "F.SilkS")
		)
		(fp_line
			(start -0.67945 0.3048)
			(end -0.67945 -0.305054)
			(stroke
				(width 0.1)
				(type default)
			)
			(layer "F.Fab")
		)
		(fp_line
			(start -0.12065 0.3048)
			(end -0.67945 0.3048)
			(stroke
				(width 0.1)
				(type default)
			)
			(layer "F.Fab")
		)
		(fp_line
			(start 0.120396 0.3048)
			(end 0.120396 0.2794)
			(stroke
				(width 0.1)
				(type default)
			)
			(layer "F.Fab")
		)
		(fp_line
			(start 0.67945 0.3048)
			(end 0.120396 0.3048)
			(stroke
				(width 0.1)
				(type default)
			)
			(layer "F.Fab")
		)
		(fp_line
			(start -0.12065 0.2794)
			(end -0.12065 0.3048)
			(stroke
				(width 0.1)
				(type default)
			)
			(layer "F.Fab")
		)
		(fp_line
			(start 0.120396 0.2794)
			(end -0.12065 0.2794)
			(stroke
				(width 0.1)
				(type default)
			)
			(layer "F.Fab")
		)
		(fp_line
			(start -0.12065 -0.2794)
			(end 0.12065 -0.2794)
			(stroke
				(width 0.1)
				(type default)
			)
			(layer "F.Fab")
		)
		(fp_line
			(start 0.12065 -0.2794)
			(end 0.12065 -0.3048)
			(stroke
				(width 0.1)
				(type default)
			)
			(layer "F.Fab")
		)
		(fp_line
			(start 0.12065 -0.3048)
			(end 0.67945 -0.3048)
			(stroke
				(width 0.1)
				(type default)
			)
			(layer "F.Fab")
		)
		(fp_line
			(start 0.67945 -0.3048)
			(end 0.67945 0.3048)
			(stroke
				(width 0.1)
				(type default)
			)
			(layer "F.Fab")
		)
		(fp_line
			(start -0.67945 -0.305054)
			(end -0.12065 -0.305054)
			(stroke
				(width 0.1)
				(type default)
			)
			(layer "F.Fab")
		)
		(fp_line
			(start -0.12065 -0.305054)
			(end -0.12065 -0.2794)
			(stroke
				(width 0.1)
				(type default)
			)
			(layer "F.Fab")
		)
		(pad "1" smd circle
			(at -0.40005 0 270)
			(size 0 0)
			(layers "F.Cu" "F.Mask" "F.Paste")
			(net "H_CPU_ERR2_LVC2_R_N")
		)
		(pad "2" smd circle
			(at 0.40005 0 270)
			(size 0 0)
			(layers "F.Cu" "F.Mask" "F.Paste")
			(net "H_CPU_ERR2_PCH_R_N")
		)
	)
	(footprint ""
		(layer "F.Cu")
		(at 12.784582 -410.802836 90)
		(property "Reference" "R2923"
			(at 0 0 90)
			(layer "F.SilkS")
			(hide yes)
			(effects
				(font
					(size 1.27 1.27)
				)
			)
		)
		(property "Value" ""
			(at 0 0 90)
			(layer "F.Fab")
			(effects
				(font
					(size 1.27 1.27)
				)
			)
		)
		(duplicate_pad_numbers_are_jumpers no)
		(fp_line
			(start 0.7874 -0.4064)
			(end 0.7874 0.4064)
			(stroke
				(width 0.1524)
				(type default)
			)
			(layer "F.SilkS")
		)
		(fp_line
			(start -0.7874 -0.4064)
			(end 0.7874 -0.4064)
			(stroke
				(width 0.1524)
				(type default)
			)
			(layer "F.SilkS")
		)
		(fp_line
			(start 0.7874 0.4064)
			(end -0.7874 0.4064)
			(stroke
				(width 0.1524)
				(type default)
			)
			(layer "F.SilkS")
		)
		(fp_line
			(start -0.7874 0.4064)
			(end -0.7874 -0.4064)
			(stroke
				(width 0.1524)
				(type default)
			)
			(layer "F.SilkS")
		)
		(fp_line
			(start -0.12065 -0.305054)
			(end -0.12065 -0.2794)
			(stroke
				(width 0.1)
				(type default)
			)
			(layer "F.Fab")
		)
		(fp_line
			(start -0.67945 -0.305054)
			(end -0.12065 -0.305054)
			(stroke
				(width 0.1)
				(type default)
			)
			(layer "F.Fab")
		)
		(fp_line
			(start 0.67945 -0.3048)
			(end 0.67945 0.3048)
			(stroke
				(width 0.1)
				(type default)
			)
			(layer "F.Fab")
		)
		(fp_line
			(start 0.12065 -0.3048)
			(end 0.67945 -0.3048)
			(stroke
				(width 0.1)
				(type default)
			)
			(layer "F.Fab")
		)
		(fp_line
			(start 0.12065 -0.2794)
			(end 0.12065 -0.3048)
			(stroke
				(width 0.1)
				(type default)
			)
			(layer "F.Fab")
		)
		(fp_line
			(start -0.12065 -0.2794)
			(end 0.12065 -0.2794)
			(stroke
				(width 0.1)
				(type default)
			)
			(layer "F.Fab")
		)
		(fp_line
			(start 0.120396 0.2794)
			(end -0.12065 0.2794)
			(stroke
				(width 0.1)
				(type default)
			)
			(layer "F.Fab")
		)
		(fp_line
			(start -0.12065 0.2794)
			(end -0.12065 0.3048)
			(stroke
				(width 0.1)
				(type default)
			)
			(layer "F.Fab")
		)
		(fp_line
			(start 0.67945 0.3048)
			(end 0.120396 0.3048)
			(stroke
				(width 0.1)
				(type default)
			)
			(layer "F.Fab")
		)
		(fp_line
			(start 0.120396 0.3048)
			(end 0.120396 0.2794)
			(stroke
				(width 0.1)
				(type default)
			)
			(layer "F.Fab")
		)
		(fp_line
			(start -0.12065 0.3048)
			(end -0.67945 0.3048)
			(stroke
				(width 0.1)
				(type default)
			)
			(layer "F.Fab")
		)
		(fp_line
			(start -0.67945 0.3048)
			(end -0.67945 -0.305054)
			(stroke
				(width 0.1)
				(type default)
			)
			(layer "F.Fab")
		)
		(pad "1" smd circle
			(at -0.40005 0 90)
			(size 0 0)
			(layers "F.Cu" "F.Mask" "F.Paste")
			(net "P3V3_AUX")
		)
		(pad "2" smd circle
			(at 0.40005 0 90)
			(size 0 0)
			(layers "F.Cu" "F.Mask" "F.Paste")
			(net "PU_U181_INT")
		)
	)
	(footprint ""
		(layer "F.Cu")
		(at 464.968336 -385.742434 90)
		(property "Reference" "PC1850"
			(at 0 0 90)
			(layer "F.SilkS")
			(hide yes)
			(effects
				(font
					(size 1.27 1.27)
				)
			)
		)
		(property "Value" ""
			(at 0 0 90)
			(layer "F.Fab")
			(effects
				(font
					(size 1.27 1.27)
				)
			)
		)
		(duplicate_pad_numbers_are_jumpers no)
		(fp_line
			(start 1.524 -0.762)
			(end 1.524 0.762)
			(stroke
				(width 0.1524)
				(type default)
			)
			(layer "F.SilkS")
		)
		(fp_line
			(start -1.524 -0.762)
			(end 1.524 -0.762)
			(stroke
				(width 0.1524)
				(type default)
			)
			(layer "F.SilkS")
		)
		(fp_line
			(start 1.524 0.762)
			(end -1.524 0.762)
			(stroke
				(width 0.1524)
				(type default)
			)
			(layer "F.SilkS")
		)
		(fp_line
			(start -1.524 0.762)
			(end -1.524 -0.762)
			(stroke
				(width 0.1524)
				(type default)
			)
			(layer "F.SilkS")
		)
		(fp_line
			(start 1.1049 -0.724916)
			(end -1.1049 -0.724916)
			(stroke
				(width 0.1)
				(type default)
			)
			(layer "F.Fab")
		)
		(fp_line
			(start -1.1049 -0.724916)
			(end -1.1049 0.724916)
			(stroke
				(width 0.1)
				(type default)
			)
			(layer "F.Fab")
		)
		(fp_line
			(start 1.1049 0.724916)
			(end 1.1049 -0.724916)
			(stroke
				(width 0.1)
				(type default)
			)
			(layer "F.Fab")
		)
		(fp_line
			(start -1.1049 0.724916)
			(end 1.1049 0.724916)
			(stroke
				(width 0.1)
				(type default)
			)
			(layer "F.Fab")
		)
		(pad "1" smd rect
			(at -0.889 0 270)
			(size 1.016 1.27)
			(layers "F.Cu" "F.Mask" "F.Paste")
			(net "SW_P5V_AUX_FLT")
		)
		(pad "2" smd rect
			(at 0.889 0 270)
			(size 1.016 1.27)
			(layers "F.Cu" "F.Mask" "F.Paste")
			(net "GND")
		)
	)
)
